(kicad_pcb
	(version 20260206)
	(generator "pcbnew")
	(generator_version "10.0")
	(general
		(thickness 1.6)
		(legacy_teardrops no)
	)
	(paper "A4")
	(title_block
		(title "12092022_DA0F0TMDCD0_F0T_Management_Board_D_brd_V3_OCP.brd")
		(comment 1 "Grand Teton / footprints 1422-1427 of 1440")
	)
	(layers
		(0 "F.Cu" signal "TOP")
		(4 "In1.Cu" signal "GND")
		(6 "In2.Cu" signal "IN1")
		(8 "In3.Cu" signal "GND1")
		(10 "In4.Cu" signal "IN2")
		(12 "In5.Cu" signal "VCC")
		(14 "In6.Cu" signal "VCC1")
		(16 "In7.Cu" signal "IN3")
		(18 "In8.Cu" signal "GND2")
		(20 "In9.Cu" signal "IN4")
		(22 "In10.Cu" signal "GND3")
		(2 "B.Cu" signal "BOTTOM")
		(9 "F.Adhes" user "F.Adhesive")
		(11 "B.Adhes" user "B.Adhesive")
		(13 "F.Paste" user "Package Geometry/Pastemask Top")
		(15 "B.Paste" user "Package Geometry/Pastemask Bottom")
		(5 "F.SilkS" user "Ref Des/Silkscreen Top")
		(7 "B.SilkS" user "Ref Des/Silkscreen Bottom")
		(1 "F.Mask" user "Board Geometry/Soldermask Top")
		(3 "B.Mask" user "Board Geometry/Soldermask Bottom")
		(17 "Dwgs.User" user "User.Drawings")
		(19 "Cmts.User" user "User.Comments")
		(21 "Eco1.User" user "User.Eco1")
		(23 "Eco2.User" user "User.Eco2")
		(25 "Edge.Cuts" user "Board Geometry/Outline")
		(27 "Margin" user)
		(31 "F.CrtYd" user "Package Geometry/Place Bound Top")
		(29 "B.CrtYd" user "Package Geometry/Place Bound Bottom")
		(35 "F.Fab" user "Ref Des/Assembly Top")
		(33 "B.Fab" user "Ref Des/Assembly Bottom")
	)
	(footprint ""
		(layer "B.Cu")
		(at 43.511216 -73.955148)
		(property "Reference" "Q11"
			(at -3.328416 -0.922782 0)
			(unlocked yes)
			(layer "B.SilkS")
			(effects
				(font
					(size 0.7874 0.5842)
					(thickness 0.1524)
				)
				(justify mirror)
			)
		)
		(property "Value" ""
			(at 0 0 0)
			(layer "B.Fab")
			(effects
				(font
					(size 1.27 1.27)
				)
				(justify mirror)
			)
		)
		(duplicate_pad_numbers_are_jumpers no)
		(fp_line
			(start -1.8796 -0.746252)
			(end -1.8796 0.803148)
			(stroke
				(width 0.1524)
				(type default)
			)
			(layer "B.SilkS")
		)
		(fp_line
			(start -1.423416 1.651)
			(end 1.8796 1.651)
			(stroke
				(width 0.1524)
				(type default)
			)
			(layer "B.SilkS")
		)
		(fp_line
			(start 1.8796 -1.651)
			(end -0.915416 -1.651)
			(stroke
				(width 0.1524)
				(type default)
			)
			(layer "B.SilkS")
		)
		(fp_line
			(start 1.8796 1.651)
			(end 1.8796 -1.651)
			(stroke
				(width 0.1524)
				(type default)
			)
			(layer "B.SilkS")
		)
		(fp_line
			(start -0.700024 -1.500124)
			(end -0.700024 1.500124)
			(stroke
				(width 0.1)
				(type default)
			)
			(layer "B.Fab")
		)
		(fp_line
			(start -0.700024 1.500124)
			(end 0.700024 1.500124)
			(stroke
				(width 0.1)
				(type default)
			)
			(layer "B.Fab")
		)
		(fp_line
			(start 0.700024 -1.500124)
			(end -0.700024 -1.500124)
			(stroke
				(width 0.1)
				(type default)
			)
			(layer "B.Fab")
		)
		(fp_line
			(start 0.700024 1.500124)
			(end 0.700024 -1.500124)
			(stroke
				(width 0.1)
				(type default)
			)
			(layer "B.Fab")
		)
		(pad "D" smd rect
			(at -1.119886 0 270)
			(size 1.016 1.2192)
			(layers "B.Cu" "B.Mask" "B.Paste")
			(net "P3V_BAT_R1")
		)
		(pad "G" smd rect
			(at 1.119886 -0.999998 270)
			(size 1.016 1.2192)
			(layers "B.Cu" "B.Mask" "B.Paste")
			(net "BATTERY_DETECT_R")
		)
		(pad "S" smd rect
			(at 1.119886 0.999998 270)
			(size 1.016 1.2192)
			(layers "B.Cu" "B.Mask" "B.Paste")
			(net "P3V_BAT_SENSOR")
		)
	)
	(footprint ""
		(layer "B.Cu")
		(at 45.405294 -30.816804 -90)
		(property "Reference" "R250"
			(at 0 0 90)
			(layer "B.SilkS")
			(hide yes)
			(effects
				(font
					(size 1.27 1.27)
				)
				(justify mirror)
			)
		)
		(property "Value" ""
			(at 0 0 90)
			(layer "B.Fab")
			(effects
				(font
					(size 1.27 1.27)
				)
				(justify mirror)
			)
		)
		(duplicate_pad_numbers_are_jumpers no)
		(fp_line
			(start -0.7874 0.4064)
			(end 0.7874 0.4064)
			(stroke
				(width 0.1524)
				(type default)
			)
			(layer "B.SilkS")
		)
		(fp_line
			(start 0.7874 0.4064)
			(end 0.7874 -0.4064)
			(stroke
				(width 0.1524)
				(type default)
			)
			(layer "B.SilkS")
		)
		(fp_line
			(start -0.7874 -0.4064)
			(end -0.7874 0.4064)
			(stroke
				(width 0.1524)
				(type default)
			)
			(layer "B.SilkS")
		)
		(fp_line
			(start 0.7874 -0.4064)
			(end -0.7874 -0.4064)
			(stroke
				(width 0.1524)
				(type default)
			)
			(layer "B.SilkS")
		)
		(fp_line
			(start -0.67945 0.3048)
			(end -0.120396 0.3048)
			(stroke
				(width 0.1)
				(type default)
			)
			(layer "B.Fab")
		)
		(fp_line
			(start -0.120396 0.3048)
			(end -0.120396 0.2794)
			(stroke
				(width 0.1)
				(type default)
			)
			(layer "B.Fab")
		)
		(fp_line
			(start 0.12065 0.3048)
			(end 0.67945 0.3048)
			(stroke
				(width 0.1)
				(type default)
			)
			(layer "B.Fab")
		)
		(fp_line
			(start 0.67945 0.3048)
			(end 0.67945 -0.305054)
			(stroke
				(width 0.1)
				(type default)
			)
			(layer "B.Fab")
		)
		(fp_line
			(start -0.120396 0.2794)
			(end 0.12065 0.2794)
			(stroke
				(width 0.1)
				(type default)
			)
			(layer "B.Fab")
		)
		(fp_line
			(start 0.12065 0.2794)
			(end 0.12065 0.3048)
			(stroke
				(width 0.1)
				(type default)
			)
			(layer "B.Fab")
		)
		(fp_line
			(start -0.12065 -0.2794)
			(end -0.12065 -0.3048)
			(stroke
				(width 0.1)
				(type default)
			)
			(layer "B.Fab")
		)
		(fp_line
			(start 0.12065 -0.2794)
			(end -0.12065 -0.2794)
			(stroke
				(width 0.1)
				(type default)
			)
			(layer "B.Fab")
		)
		(fp_line
			(start -0.67945 -0.3048)
			(end -0.67945 0.3048)
			(stroke
				(width 0.1)
				(type default)
			)
			(layer "B.Fab")
		)
		(fp_line
			(start -0.12065 -0.3048)
			(end -0.67945 -0.3048)
			(stroke
				(width 0.1)
				(type default)
			)
			(layer "B.Fab")
		)
		(fp_line
			(start 0.12065 -0.305054)
			(end 0.12065 -0.2794)
			(stroke
				(width 0.1)
				(type default)
			)
			(layer "B.Fab")
		)
		(fp_line
			(start 0.67945 -0.305054)
			(end 0.12065 -0.305054)
			(stroke
				(width 0.1)
				(type default)
			)
			(layer "B.Fab")
		)
		(pad "1" smd circle
			(at 0.40005 0 90)
			(size 0 0)
			(layers "B.Cu" "B.Mask" "B.Paste")
			(net "P3V3_AUX")
		)
		(pad "2" smd circle
			(at -0.40005 0 90)
			(size 0 0)
			(layers "B.Cu" "B.Mask" "B.Paste")
			(net "SMB_BMC_MM4_SCL")
		)
	)
	(footprint ""
		(layer "B.Cu")
		(at 67.4116 -106.4387 -90)
		(property "Reference" "R36"
			(at 0 0 90)
			(layer "B.SilkS")
			(hide yes)
			(effects
				(font
					(size 1.27 1.27)
				)
				(justify mirror)
			)
		)
		(property "Value" ""
			(at 0 0 90)
			(layer "B.Fab")
			(effects
				(font
					(size 1.27 1.27)
				)
				(justify mirror)
			)
		)
		(duplicate_pad_numbers_are_jumpers no)
		(fp_line
			(start -0.7874 0.4064)
			(end 0.7874 0.4064)
			(stroke
				(width 0.1524)
				(type default)
			)
			(layer "B.SilkS")
		)
		(fp_line
			(start 0.7874 0.4064)
			(end 0.7874 -0.4064)
			(stroke
				(width 0.1524)
				(type default)
			)
			(layer "B.SilkS")
		)
		(fp_line
			(start -0.7874 -0.4064)
			(end -0.7874 0.4064)
			(stroke
				(width 0.1524)
				(type default)
			)
			(layer "B.SilkS")
		)
		(fp_line
			(start 0.7874 -0.4064)
			(end -0.7874 -0.4064)
			(stroke
				(width 0.1524)
				(type default)
			)
			(layer "B.SilkS")
		)
		(fp_line
			(start -0.67945 0.3048)
			(end -0.120396 0.3048)
			(stroke
				(width 0.1)
				(type default)
			)
			(layer "B.Fab")
		)
		(fp_line
			(start -0.120396 0.3048)
			(end -0.120396 0.2794)
			(stroke
				(width 0.1)
				(type default)
			)
			(layer "B.Fab")
		)
		(fp_line
			(start 0.12065 0.3048)
			(end 0.67945 0.3048)
			(stroke
				(width 0.1)
				(type default)
			)
			(layer "B.Fab")
		)
		(fp_line
			(start 0.67945 0.3048)
			(end 0.67945 -0.305054)
			(stroke
				(width 0.1)
				(type default)
			)
			(layer "B.Fab")
		)
		(fp_line
			(start -0.120396 0.2794)
			(end 0.12065 0.2794)
			(stroke
				(width 0.1)
				(type default)
			)
			(layer "B.Fab")
		)
		(fp_line
			(start 0.12065 0.2794)
			(end 0.12065 0.3048)
			(stroke
				(width 0.1)
				(type default)
			)
			(layer "B.Fab")
		)
		(fp_line
			(start -0.12065 -0.2794)
			(end -0.12065 -0.3048)
			(stroke
				(width 0.1)
				(type default)
			)
			(layer "B.Fab")
		)
		(fp_line
			(start 0.12065 -0.2794)
			(end -0.12065 -0.2794)
			(stroke
				(width 0.1)
				(type default)
			)
			(layer "B.Fab")
		)
		(fp_line
			(start -0.67945 -0.3048)
			(end -0.67945 0.3048)
			(stroke
				(width 0.1)
				(type default)
			)
			(layer "B.Fab")
		)
		(fp_line
			(start -0.12065 -0.3048)
			(end -0.67945 -0.3048)
			(stroke
				(width 0.1)
				(type default)
			)
			(layer "B.Fab")
		)
		(fp_line
			(start 0.12065 -0.305054)
			(end 0.12065 -0.2794)
			(stroke
				(width 0.1)
				(type default)
			)
			(layer "B.Fab")
		)
		(fp_line
			(start 0.67945 -0.305054)
			(end 0.12065 -0.305054)
			(stroke
				(width 0.1)
				(type default)
			)
			(layer "B.Fab")
		)
		(pad "1" smd circle
			(at 0.40005 0 90)
			(size 0 0)
			(layers "B.Cu" "B.Mask" "B.Paste")
			(net "SMB_BMC_MM14_SCL")
		)
		(pad "2" smd circle
			(at -0.40005 0 90)
			(size 0 0)
			(layers "B.Cu" "B.Mask" "B.Paste")
			(net "SMB_BMC_MM14_R1_SCL")
		)
	)
	(footprint ""
		(layer "B.Cu")
		(at 45.085 -92.5322 -90)
		(property "Reference" "C219"
			(at 0 0 90)
			(layer "B.SilkS")
			(hide yes)
			(effects
				(font
					(size 1.27 1.27)
				)
				(justify mirror)
			)
		)
		(property "Value" ""
			(at 0 0 90)
			(layer "B.Fab")
			(effects
				(font
					(size 1.27 1.27)
				)
				(justify mirror)
			)
		)
		(duplicate_pad_numbers_are_jumpers no)
		(fp_line
			(start -0.7874 0.4064)
			(end 0.7874 0.4064)
			(stroke
				(width 0.1524)
				(type default)
			)
			(layer "B.SilkS")
		)
		(fp_line
			(start 0.7874 0.4064)
			(end 0.7874 -0.4064)
			(stroke
				(width 0.1524)
				(type default)
			)
			(layer "B.SilkS")
		)
		(fp_line
			(start -0.7874 -0.4064)
			(end -0.7874 0.4064)
			(stroke
				(width 0.1524)
				(type default)
			)
			(layer "B.SilkS")
		)
		(fp_line
			(start 0.7874 -0.4064)
			(end -0.7874 -0.4064)
			(stroke
				(width 0.1524)
				(type default)
			)
			(layer "B.SilkS")
		)
		(fp_line
			(start -0.67945 0.3048)
			(end -0.120396 0.3048)
			(stroke
				(width 0.1)
				(type default)
			)
			(layer "B.Fab")
		)
		(fp_line
			(start -0.120396 0.3048)
			(end -0.120396 0.2794)
			(stroke
				(width 0.1)
				(type default)
			)
			(layer "B.Fab")
		)
		(fp_line
			(start 0.12065 0.3048)
			(end 0.67945 0.3048)
			(stroke
				(width 0.1)
				(type default)
			)
			(layer "B.Fab")
		)
		(fp_line
			(start 0.67945 0.3048)
			(end 0.67945 -0.305054)
			(stroke
				(width 0.1)
				(type default)
			)
			(layer "B.Fab")
		)
		(fp_line
			(start -0.120396 0.2794)
			(end 0.12065 0.2794)
			(stroke
				(width 0.1)
				(type default)
			)
			(layer "B.Fab")
		)
		(fp_line
			(start 0.12065 0.2794)
			(end 0.12065 0.3048)
			(stroke
				(width 0.1)
				(type default)
			)
			(layer "B.Fab")
		)
		(fp_line
			(start -0.12065 -0.2794)
			(end -0.12065 -0.3048)
			(stroke
				(width 0.1)
				(type default)
			)
			(layer "B.Fab")
		)
		(fp_line
			(start 0.12065 -0.2794)
			(end -0.12065 -0.2794)
			(stroke
				(width 0.1)
				(type default)
			)
			(layer "B.Fab")
		)
		(fp_line
			(start -0.67945 -0.3048)
			(end -0.67945 0.3048)
			(stroke
				(width 0.1)
				(type default)
			)
			(layer "B.Fab")
		)
		(fp_line
			(start -0.12065 -0.3048)
			(end -0.67945 -0.3048)
			(stroke
				(width 0.1)
				(type default)
			)
			(layer "B.Fab")
		)
		(fp_line
			(start 0.12065 -0.305054)
			(end 0.12065 -0.2794)
			(stroke
				(width 0.1)
				(type default)
			)
			(layer "B.Fab")
		)
		(fp_line
			(start 0.67945 -0.305054)
			(end 0.12065 -0.305054)
			(stroke
				(width 0.1)
				(type default)
			)
			(layer "B.Fab")
		)
		(pad "1" smd circle
			(at 0.40005 0 90)
			(size 0 0)
			(layers "B.Cu" "B.Mask" "B.Paste")
			(net "P3V3_AUX")
		)
		(pad "2" smd circle
			(at -0.40005 0 90)
			(size 0 0)
			(layers "B.Cu" "B.Mask" "B.Paste")
			(net "GND")
		)
	)
	(footprint ""
		(layer "B.Cu")
		(at 81.686908 -47.98568 -90)
		(property "Reference" "R367"
			(at 0 0 90)
			(layer "B.SilkS")
			(hide yes)
			(effects
				(font
					(size 1.27 1.27)
				)
				(justify mirror)
			)
		)
		(property "Value" ""
			(at 0 0 90)
			(layer "B.Fab")
			(effects
				(font
					(size 1.27 1.27)
				)
				(justify mirror)
			)
		)
		(duplicate_pad_numbers_are_jumpers no)
		(fp_line
			(start -0.7874 0.4064)
			(end 0.7874 0.4064)
			(stroke
				(width 0.1524)
				(type default)
			)
			(layer "B.SilkS")
		)
		(fp_line
			(start 0.7874 0.4064)
			(end 0.7874 -0.4064)
			(stroke
				(width 0.1524)
				(type default)
			)
			(layer "B.SilkS")
		)
		(fp_line
			(start -0.7874 -0.4064)
			(end -0.7874 0.4064)
			(stroke
				(width 0.1524)
				(type default)
			)
			(layer "B.SilkS")
		)
		(fp_line
			(start 0.7874 -0.4064)
			(end -0.7874 -0.4064)
			(stroke
				(width 0.1524)
				(type default)
			)
			(layer "B.SilkS")
		)
		(fp_line
			(start -0.67945 0.3048)
			(end -0.120396 0.3048)
			(stroke
				(width 0.1)
				(type default)
			)
			(layer "B.Fab")
		)
		(fp_line
			(start -0.120396 0.3048)
			(end -0.120396 0.2794)
			(stroke
				(width 0.1)
				(type default)
			)
			(layer "B.Fab")
		)
		(fp_line
			(start 0.12065 0.3048)
			(end 0.67945 0.3048)
			(stroke
				(width 0.1)
				(type default)
			)
			(layer "B.Fab")
		)
		(fp_line
			(start 0.67945 0.3048)
			(end 0.67945 -0.305054)
			(stroke
				(width 0.1)
				(type default)
			)
			(layer "B.Fab")
		)
		(fp_line
			(start -0.120396 0.2794)
			(end 0.12065 0.2794)
			(stroke
				(width 0.1)
				(type default)
			)
			(layer "B.Fab")
		)
		(fp_line
			(start 0.12065 0.2794)
			(end 0.12065 0.3048)
			(stroke
				(width 0.1)
				(type default)
			)
			(layer "B.Fab")
		)
		(fp_line
			(start -0.12065 -0.2794)
			(end -0.12065 -0.3048)
			(stroke
				(width 0.1)
				(type default)
			)
			(layer "B.Fab")
		)
		(fp_line
			(start 0.12065 -0.2794)
			(end -0.12065 -0.2794)
			(stroke
				(width 0.1)
				(type default)
			)
			(layer "B.Fab")
		)
		(fp_line
			(start -0.67945 -0.3048)
			(end -0.67945 0.3048)
			(stroke
				(width 0.1)
				(type default)
			)
			(layer "B.Fab")
		)
		(fp_line
			(start -0.12065 -0.3048)
			(end -0.67945 -0.3048)
			(stroke
				(width 0.1)
				(type default)
			)
			(layer "B.Fab")
		)
		(fp_line
			(start 0.12065 -0.305054)
			(end 0.12065 -0.2794)
			(stroke
				(width 0.1)
				(type default)
			)
			(layer "B.Fab")
		)
		(fp_line
			(start 0.67945 -0.305054)
			(end 0.12065 -0.305054)
			(stroke
				(width 0.1)
				(type default)
			)
			(layer "B.Fab")
		)
		(pad "1" smd circle
			(at 0.40005 0 90)
			(size 0 0)
			(layers "B.Cu" "B.Mask" "B.Paste")
			(net "M_BMC_DDR4_MRAS_N")
		)
		(pad "2" smd circle
			(at -0.40005 0 90)
			(size 0 0)
			(layers "B.Cu" "B.Mask" "B.Paste")
			(net "P1V2_AUX")
		)
	)
	(footprint ""
		(layer "B.Cu")
		(at 14.859 -93.3958 180)
		(property "Reference" "R263"
			(at 0 0 0)
			(layer "B.SilkS")
			(hide yes)
			(effects
				(font
					(size 1.27 1.27)
				)
				(justify mirror)
			)
		)
		(property "Value" ""
			(at 0 0 0)
			(layer "B.Fab")
			(effects
				(font
					(size 1.27 1.27)
				)
				(justify mirror)
			)
		)
		(duplicate_pad_numbers_are_jumpers no)
		(fp_line
			(start 0.7874 0.4064)
			(end 0.7874 -0.4064)
			(stroke
				(width 0.1524)
				(type default)
			)
			(layer "B.SilkS")
		)
		(fp_line
			(start 0.7874 -0.4064)
			(end -0.7874 -0.4064)
			(stroke
				(width 0.1524)
				(type default)
			)
			(layer "B.SilkS")
		)
		(fp_line
			(start -0.7874 0.4064)
			(end 0.7874 0.4064)
			(stroke
				(width 0.1524)
				(type default)
			)
			(layer "B.SilkS")
		)
		(fp_line
			(start -0.7874 -0.4064)
			(end -0.7874 0.4064)
			(stroke
				(width 0.1524)
				(type default)
			)
			(layer "B.SilkS")
		)
		(fp_line
			(start 0.67945 0.3048)
			(end 0.67945 -0.305054)
			(stroke
				(width 0.1)
				(type default)
			)
			(layer "B.Fab")
		)
		(fp_line
			(start 0.67945 -0.305054)
			(end 0.12065 -0.305054)
			(stroke
				(width 0.1)
				(type default)
			)
			(layer "B.Fab")
		)
		(fp_line
			(start 0.12065 0.3048)
			(end 0.67945 0.3048)
			(stroke
				(width 0.1)
				(type default)
			)
			(layer "B.Fab")
		)
		(fp_line
			(start 0.12065 0.2794)
			(end 0.12065 0.3048)
			(stroke
				(width 0.1)
				(type default)
			)
			(layer "B.Fab")
		)
		(fp_line
			(start 0.12065 -0.2794)
			(end -0.12065 -0.2794)
			(stroke
				(width 0.1)
				(type default)
			)
			(layer "B.Fab")
		)
		(fp_line
			(start 0.12065 -0.305054)
			(end 0.12065 -0.2794)
			(stroke
				(width 0.1)
				(type default)
			)
			(layer "B.Fab")
		)
		(fp_line
			(start -0.120396 0.3048)
			(end -0.120396 0.2794)
			(stroke
				(width 0.1)
				(type default)
			)
			(layer "B.Fab")
		)
		(fp_line
			(start -0.120396 0.2794)
			(end 0.12065 0.2794)
			(stroke
				(width 0.1)
				(type default)
			)
			(layer "B.Fab")
		)
		(fp_line
			(start -0.12065 -0.2794)
			(end -0.12065 -0.3048)
			(stroke
				(width 0.1)
				(type default)
			)
			(layer "B.Fab")
		)
		(fp_line
			(start -0.12065 -0.3048)
			(end -0.67945 -0.3048)
			(stroke
				(width 0.1)
				(type default)
			)
			(layer "B.Fab")
		)
		(fp_line
			(start -0.67945 0.3048)
			(end -0.120396 0.3048)
			(stroke
				(width 0.1)
				(type default)
			)
			(layer "B.Fab")
		)
		(fp_line
			(start -0.67945 -0.3048)
			(end -0.67945 0.3048)
			(stroke
				(width 0.1)
				(type default)
			)
			(layer "B.Fab")
		)
		(pad "1" smd circle
			(at 0.40005 0)
			(size 0 0)
			(layers "B.Cu" "B.Mask" "B.Paste")
			(net "RST_MB_STBY_N")
		)
		(pad "2" smd circle
			(at -0.40005 0)
			(size 0 0)
			(layers "B.Cu" "B.Mask" "B.Paste")
			(net "RST_MB_STBY_R_N")
		)
	)
)
